# T6G (Grand Teton) — schematic netlist excerpt (pin names and nets, part order shuffled) for the footprints in the layout excerpt that follows; sources: Cadence DE-HDL packaged netlist, KiCad conversion of 04192023_DAF0TMB3IC0_F0TG_MB_C_brd_V02_OCP.brd

J23  SCONN288_DDR506112002KQ  IO  pkg DDR288S_1-1VXC  page 91
  VIN_BULK0  = P12V_MEM_CPU0
  RFU0  = NC
  VIN_MGMT  = P3V3_AUX
  HSCL  = I3C_SPD_DDRF_CPU0_SCL
  HSDA  = I3C_SPD_DDRF_CPU0_SDA
  VSS0  = GND
  DQ0_A  = M_F_CPU0_SA_DQ<0>
  VSS1  = GND
  DQ1_A  = M_F_CPU0_SA_DQ<1>
  VSS2  = GND
  DQS0_A_T  = M_F_CPU0_SA_DQS_DP<0>
  DQS0_A_C  = M_F_CPU0_SA_DQS_DN<0>
  VSS3  = GND
  DQ4_A  = M_F_CPU0_SA_DQ<4>
  VSS4  = GND
  DQ5_A  = M_F_CPU0_SA_DQ<5>
  VSS5  = GND
  DQ8_A  = M_F_CPU0_SA_DQ<8>
  VSS6  = GND
  DQ9_A  = M_F_CPU0_SA_DQ<9>
  VSS7  = GND
  DQS1_A_T  = M_F_CPU0_SA_DQS_DP<1>
  DQS1_A_C  = M_F_CPU0_SA_DQS_DN<1>
  VSS8  = GND
  DQ12_A  = M_F_CPU0_SA_DQ<12>
  VSS9  = GND
  DQ13_A  = M_F_CPU0_SA_DQ<13>
  VSS10  = GND
  DQ16_A  = M_F_CPU0_SA_DQ<16>
  VSS11  = GND
  DQ17_A  = M_F_CPU0_SA_DQ<17>
  VSS12  = GND
  DQS2_A_T  = M_F_CPU0_SA_DQS_DP<2>
  DQS2_A_C  = M_F_CPU0_SA_DQS_DN<2>
  VSS13  = GND
  DQ20_A  = M_F_CPU0_SA_DQ<20>
  VSS14  = GND
  DQ21_A  = M_F_CPU0_SA_DQ<21>
  VSS15  = GND
  DQ24_A  = M_F_CPU0_SA_DQ<24>
  VSS16  = GND
  DQ25_A  = M_F_CPU0_SA_DQ<25>
  VSS17  = GND
  DQS3_A_T  = M_F_CPU0_SA_DQS_DP<3>
  DQS3_A_C  = M_F_CPU0_SA_DQS_DN<3>
  VSS18  = GND
  DQ28_A  = M_F_CPU0_SA_DQ<28>
  VSS19  = GND
  DQ29_A  = M_F_CPU0_SA_DQ<29>
  VSS20  = GND
  CB0_A  = M_F_CPU0_SA_CB<0>
  VSS21  = GND
  CB1_A  = M_F_CPU0_SA_CB<1>
  VSS22  = GND
  DQS4_A_T  = M_F_CPU0_SA_DQS_DP<4>
  DQS4_A_C  = M_F_CPU0_SA_DQS_DN<4>
  VSS23  = GND
  CB4_A  = M_F_CPU0_SA_CB<4>
  VSS24  = GND
  CB5_A  = M_F_CPU0_SA_CB<5>
  VSS25  = GND
  ALERT_N  = M_F_CPU0_ALERT_N
  VSS26  = GND
  CS0_A_N  = M_F_CPU0_SA_CS_N<0>
  VSS27  = GND
  CA0_A  = M_F_CPU0_SA_CA<0>
  VSS28  = GND
  CA2_A  = M_F_CPU0_SA_CA<2>
  VSS29  = GND
  CA4_A  = M_F_CPU0_SA_CA<4>
  VSS30  = GND
  CA6_A  = M_F_CPU0_SA_CA<6>
  VSS31  = GND
  PAR_A  = M_F_CPU0_SA_PAR
  VSS32  = GND
  CA0_B  = M_F_CPU0_SB_CA<0>
  VSS33  = GND
  CA2_B  = M_F_CPU0_SB_CA<2>
  VSS34  = GND
  CA4_B  = M_F_CPU0_SB_CA<4>
  VSS35  = GND
  CA6_B  = M_F_CPU0_SB_CA<6>
  VSS36  = GND
  CS0_B_N  = M_F_CPU0_SB_CS_N<0>
  VSS37  = GND
  \lbd||rsp_a_n\  = M_F_CPU0_SA_RSP<0>
  \lbs||rsp_b_n\  = M_F_CPU0_SB_RSP<0>
  VSS38  = GND
  CB4_B  = M_F_CPU0_SB_CB<4>
  VSS39  = GND
  CB5_B  = M_F_CPU0_SB_CB<5>
  VSS40  = GND
  \dqs9_b_t||tdqs9_b_t||dbi4_b_n\  = M_F_CPU0_SB_DQS_DP<9>
  \dqs9_b_c||tdqs9_b_c\  = M_F_CPU0_SB_DQS_DN<9>
  VSS41  = GND
  CB0_B  = M_F_CPU0_SB_CB<0>
  VSS42  = GND
  CB1_B  = M_F_CPU0_SB_CB<1>
  VSS43  = GND
  DQ0_B  = M_F_CPU0_SB_DQ<0>
  VSS44  = GND
  DQ1_B  = M_F_CPU0_SB_DQ<1>
  VSS45  = GND
  DQS0_B_T  = M_F_CPU0_SB_DQS_DP<0>
  DQS0_B_C  = M_F_CPU0_SB_DQS_DN<0>
  VSS46  = GND
  DQ4_B  = M_F_CPU0_SB_DQ<4>
  VSS47  = GND
  DQ5_B  = M_F_CPU0_SB_DQ<5>
  VSS48  = GND
  DQ8_B  = M_F_CPU0_SB_DQ<8>
  VSS49  = GND
  DQ9_B  = M_F_CPU0_SB_DQ<9>
  VSS50  = GND
  DQS1_B_T  = M_F_CPU0_SB_DQS_DP<1>
  DQS1_B_C  = M_F_CPU0_SB_DQS_DN<1>
  VSS51  = GND
  DQ12_B  = M_F_CPU0_SB_DQ<12>
  VSS52  = GND
  DQ13_B  = M_F_CPU0_SB_DQ<13>
  VSS53  = GND
  DQ16_B  = M_F_CPU0_SB_DQ<16>
  VSS54  = GND
  DQ17_B  = M_F_CPU0_SB_DQ<17>
  VSS55  = GND
  DQS2_B_T  = M_F_CPU0_SB_DQS_DP<2>
  DQS2_B_C  = M_F_CPU0_SB_DQS_DN<2>
  VSS56  = GND
  DQ20_B  = M_F_CPU0_SB_DQ<20>
  VSS57  = GND
  DQ21_B  = M_F_CPU0_SB_DQ<21>
  VSS58  = GND
  DQ24_B  = M_F_CPU0_SB_DQ<24>
  VSS59  = GND
  DQ25_B  = M_F_CPU0_SB_DQ<25>
  VSS60  = GND
  DQS3_B_T  = M_F_CPU0_SB_DQS_DP<3>
  DQS3_B_C  = M_F_CPU0_SB_DQS_DN<3>
  VSS61  = GND
  DQ28_B  = M_F_CPU0_SB_DQ<28>
  VSS62  = GND
  DQ29_B  = M_F_CPU0_SB_DQ<29>
  VSS63  = GND
  RFU1  = NC
  VIN_BULK1  = P12V_MEM_CPU0
  VIN_BULK2  = P12V_MEM_CPU0
  \pwr_good||fail_n\  = PWRGD_CHF_CPU0_DIMM
  HAS  = PD_CHF_CPU0_DIMM_SAA
  RFU2  = NC
  RFU3  = NC
  VSS64  = GND
  DQ2_A  = M_F_CPU0_SA_DQ<2>
  VSS65  = GND
  DQ3_A  = M_F_CPU0_SA_DQ<3>
  VSS66  = GND
  \dqs5_a_c||tdqs5_a_c||dqs5_a_t||tdqs5_a_t\  = M_F_CPU0_SA_DQS_DN<5>
  \dqs5_a_t||tdqs5_a_t\  = M_F_CPU0_SA_DQS_DP<5>
  VSS67  = GND
  DQ6_A  = M_F_CPU0_SA_DQ<6>
  VSS68  = GND
  DQ7_A  = M_F_CPU0_SA_DQ<7>
  VSS69  = GND
  DQ10_A  = M_F_CPU0_SA_DQ<10>
  VSS70  = GND
  DQ11_A  = M_F_CPU0_SA_DQ<11>
  VSS71  = GND
  \dqs6_a_c||tdqs6_a_c||dqs6_a_t||tdqs6_a_t\  = M_F_CPU0_SA_DQS_DN<6>
  \dqs6_a_t||tdqs6_a_t\  = M_F_CPU0_SA_DQS_DP<6>
  VSS72  = GND
  DQ14_A  = M_F_CPU0_SA_DQ<14>
  VSS73  = GND
  DQ15_A  = M_F_CPU0_SA_DQ<15>
  VSS74  = GND
  DQ18_A  = M_F_CPU0_SA_DQ<18>
  VSS75  = GND
  DQ19_A  = M_F_CPU0_SA_DQ<19>
  VSS76  = GND
  \dqs7_a_c||tdqs7_a_c\  = M_F_CPU0_SA_DQS_DN<7>
  \dqs7_a_t||tdqs7_a_t\  = M_F_CPU0_SA_DQS_DP<7>
  VSS77  = GND
  DQ22_A  = M_F_CPU0_SA_DQ<22>
  VSS78  = GND
  DQ23_A  = M_F_CPU0_SA_DQ<23>
  VSS79  = GND
  DQ26_A  = M_F_CPU0_SA_DQ<26>
  VSS80  = GND
  DQ27_A  = M_F_CPU0_SA_DQ<27>
  VSS81  = GND
  \dqs8_a_c||tdqs8_a_c\  = M_F_CPU0_SA_DQS_DN<8>
  \dqs8_a_t||tdqs8_a_t\  = M_F_CPU0_SA_DQS_DP<8>
  VSS82  = GND
  DQ30_A  = M_F_CPU0_SA_DQ<30>
  VSS83  = GND
  DQ31_A  = M_F_CPU0_SA_DQ<31>
  VSS84  = GND
  CB2_A  = M_F_CPU0_SA_CB<2>
  VSS85  = GND
  CB3_A  = M_F_CPU0_SA_CB<3>
  VSS86  = GND
  \dqs9_a_c||tdqs9_a_c\  = M_F_CPU0_SA_DQS_DN<9>
  \dqs9_a_t||tdqs9_a_t\  = M_F_CPU0_SA_DQS_DP<9>
  VSS87  = GND
  CB6_A  = M_F_CPU0_SA_CB<6>
  VSS88  = GND
  CB7_A  = M_F_CPU0_SA_CB<7>
  VSS89  = GND
  RESET_N  = M_F_CPU0_RESET_N
  VSS90  = GND
  CS1_A_N  = M_F_CPU0_SA_CS_N<1>
  VSS91  = GND
  CA1_A  = M_F_CPU0_SA_CA<1>
  VSS92  = GND
  CA3_A  = M_F_CPU0_SA_CA<3>
  VSS93  = GND
  CA5_A  = M_F_CPU0_SA_CA<5>
  VSS94  = GND
  CK_T  = M_F_CPU0_CLK_DP<0>
  CK_C  = M_F_CPU0_CLK_DN<0>
  VSS95  = GND
  RFU4  = NC
  CA1_B  = M_F_CPU0_SB_CA<1>
  VSS96  = GND
  CA3_B  = M_F_CPU0_SB_CA<3>
  VSS97  = GND
  CA5_B  = M_F_CPU0_SB_CA<5>
  VSS98  = GND
  PAR_B  = M_F_CPU0_SB_PAR
  VSS99  = GND
  CS1_B_N  = M_F_CPU0_SB_CS_N<1>
  VSS100  = GND
  RFU5  = NC
  RFU6  = NC
  VSS101  = GND
  CB6_B  = M_F_CPU0_SB_CB<6>
  VSS102  = GND
  CB7_B  = M_F_CPU0_SB_CB<7>
  VSS103  = GND
  DQS4_B_C  = M_F_CPU0_SB_DQS_DN<4>
  DQS4_B_T  = M_F_CPU0_SB_DQS_DP<4>
  VSS104  = GND
  CB2_B  = M_F_CPU0_SB_CB<2>
  VSS105  = GND
  CB3_B  = M_F_CPU0_SB_CB<3>
  VSS106  = GND
  DQ2_B  = M_F_CPU0_SB_DQ<2>
  VSS107  = GND
  DQ3_B  = M_F_CPU0_SB_DQ<3>
  VSS108  = GND
  \dqs5_b_c||tdqs5_b_c\  = M_F_CPU0_SB_DQS_DN<5>
  \dqs5_b_t||tdqs5_b_t\  = M_F_CPU0_SB_DQS_DP<5>
  VSS109  = GND
  DQ6_B  = M_F_CPU0_SB_DQ<6>
  VSS110  = GND
  DQ7_B  = M_F_CPU0_SB_DQ<7>
  VSS111  = GND
  DQ10_B  = M_F_CPU0_SB_DQ<10>
  VSS112  = GND
  DQ11_B  = M_F_CPU0_SB_DQ<11>
  VSS113  = GND
  \dqs6_b_c||tdqs6_b_c\  = M_F_CPU0_SB_DQS_DN<6>
  \dqs6_b_t||tdqs6_b_t\  = M_F_CPU0_SB_DQS_DP<6>
  VSS114  = GND
  DQ14_B  = M_F_CPU0_SB_DQ<14>
  VSS115  = GND
  DQ15_B  = M_F_CPU0_SB_DQ<15>
  VSS116  = GND
  DQ18_B  = M_F_CPU0_SB_DQ<18>
  VSS117  = GND
  DQ19_B  = M_F_CPU0_SB_DQ<19>
  VSS118  = GND
  \dqs7_b_c||tdqs7_b_c\  = M_F_CPU0_SB_DQS_DN<7>
  \dqs7_b_t||tdqs7_b_t\  = M_F_CPU0_SB_DQS_DP<7>
  VSS119  = GND
  DQ22_B  = M_F_CPU0_SB_DQ<22>
  VSS120  = GND
  DQ23_B  = M_F_CPU0_SB_DQ<23>
  VSS121  = GND
  DQ26_B  = M_F_CPU0_SB_DQ<26>
  VSS122  = GND
  DQ27_B  = M_F_CPU0_SB_DQ<27>
  VSS123  = GND
  \dqs8_b_c||tdqs8_b_c\  = M_F_CPU0_SB_DQS_DN<8>
  \dqs8_b_t||tdqs8_b_t\  = M_F_CPU0_SB_DQS_DP<8>
  VSS124  = GND
  DQ30_B  = M_F_CPU0_SB_DQ<30>
  VSS125  = GND
  DQ31_B  = M_F_CPU0_SB_DQ<31>
  VSS126  = GND
  G1  = GND
  G2  = GND
  G3  = GND

(kicad_pcb
	(version 20260206)
	(generator "pcbnew")
	(generator_version "10.0")
	(general
		(thickness 1.6)
		(legacy_teardrops no)
	)
	(paper "A4")
	(title_block
		(title "04192023_DAF0TMB3IC0_F0TG_MB_C_brd_V02_OCP.brd")
		(comment 1 "Grand Teton / footprint 2449 of 8354 (J23), pads 1-46 of 291")
	)
	(layers
		(0 "F.Cu" signal "TOP")
		(4 "In1.Cu" signal "GND")
		(6 "In2.Cu" signal "IN1")
		(8 "In3.Cu" signal "GND1")
		(10 "In4.Cu" signal "IN2")
		(12 "In5.Cu" signal "GND2")
		(14 "In6.Cu" signal "IN3")
		(16 "In7.Cu" signal "GND3")
		(18 "In8.Cu" signal "VCC")
		(20 "In9.Cu" signal "VCC1")
		(22 "In10.Cu" signal "GND4")
		(24 "In11.Cu" signal "IN4")
		(26 "In12.Cu" signal "GND5")
		(28 "In13.Cu" signal "IN5")
		(30 "In14.Cu" signal "GND6")
		(32 "In15.Cu" signal "IN6")
		(34 "In16.Cu" signal "GND7")
		(2 "B.Cu" signal "BOTTOM")
		(9 "F.Adhes" user "F.Adhesive")
		(11 "B.Adhes" user "B.Adhesive")
		(13 "F.Paste" user "Package Geometry/Pastemask Top")
		(15 "B.Paste" user "Package Geometry/Pastemask Bottom")
		(5 "F.SilkS" user "Ref Des/Silkscreen Top")
		(7 "B.SilkS" user "Ref Des/Silkscreen Bottom")
		(1 "F.Mask" user "Board Geometry/Soldermask Top")
		(3 "B.Mask" user "Board Geometry/Soldermask Bottom")
		(17 "Dwgs.User" user "User.Drawings")
		(19 "Cmts.User" user "User.Comments")
		(21 "Eco1.User" user "User.Eco1")
		(23 "Eco2.User" user "User.Eco2")
		(25 "Edge.Cuts" user "Board Geometry/Outline")
		(27 "Margin" user)
		(31 "F.CrtYd" user "Package Geometry/Place Bound Top")
		(29 "B.CrtYd" user "Package Geometry/Place Bound Bottom")
		(35 "F.Fab" user "Ref Des/Assembly Top")
		(33 "B.Fab" user "Ref Des/Assembly Bottom")
	)
	(footprint ""
		(layer "F.Cu")
		(at 267.598144 -255.560068 180)
		(property "Reference" "J23"
			(at -2.2098 -81.984088 0)
			(unlocked yes)
			(layer "F.SilkS")
			(effects
				(font
					(size 0.7874 0.5842)
					(thickness 0.1524)
				)
			)
		)
		(property "Value" ""
			(at 0 0 180)
			(layer "F.Fab")
			(effects
				(font
					(size 1.27 1.27)
				)
			)
		)
		(duplicate_pad_numbers_are_jumpers no)
		(pad "1" smd rect
			(at -2.050034 -63.324994 90)
			(size 0.519938 1.4986)
			(layers "F.Cu" "F.Mask" "F.Paste")
			(net "P12V_MEM_CPU0")
		)
		(pad "2" smd rect
			(at -2.050034 -62.47511 90)
			(size 0.519938 1.4986)
			(layers "F.Cu" "F.Mask" "F.Paste")
			(net "Net_2319")
		)
		(pad "3" smd rect
			(at -2.050034 -61.624972 90)
			(size 0.519938 1.4986)
			(layers "F.Cu" "F.Mask" "F.Paste")
			(net "P3V3_AUX")
		)
		(pad "4" smd rect
			(at -2.050034 -60.775088 90)
			(size 0.519938 1.4986)
			(layers "F.Cu" "F.Mask" "F.Paste")
			(net "I3C_SPD_DDRF_CPU0_SCL")
		)
		(pad "5" smd rect
			(at -2.050034 -59.92495 90)
			(size 0.519938 1.4986)
			(layers "F.Cu" "F.Mask" "F.Paste")
			(net "I3C_SPD_DDRF_CPU0_SDA")
		)
		(pad "6" smd rect
			(at -2.050034 -59.075066 90)
			(size 0.519938 1.4986)
			(layers "F.Cu" "F.Mask" "F.Paste")
			(net "GND")
		)
		(pad "7" smd rect
			(at -2.050034 -58.224928 90)
			(size 0.519938 1.4986)
			(layers "F.Cu" "F.Mask" "F.Paste")
			(net "M_F_CPU0_SA_DQ<0>")
		)
		(pad "8" smd rect
			(at -2.050034 -57.375044 90)
			(size 0.519938 1.4986)
			(layers "F.Cu" "F.Mask" "F.Paste")
			(net "GND")
		)
		(pad "9" smd rect
			(at -2.050034 -56.524906 90)
			(size 0.519938 1.4986)
			(layers "F.Cu" "F.Mask" "F.Paste")
			(net "M_F_CPU0_SA_DQ<1>")
		)
		(pad "10" smd rect
			(at -2.050034 -55.675022 90)
			(size 0.519938 1.4986)
			(layers "F.Cu" "F.Mask" "F.Paste")
			(net "GND")
		)
		(pad "11" smd rect
			(at -2.050034 -54.824884 90)
			(size 0.519938 1.4986)
			(layers "F.Cu" "F.Mask" "F.Paste")
			(net "M_F_CPU0_SA_DQS_DP<0>")
		)
		(pad "12" smd rect
			(at -2.050034 -53.975 90)
			(size 0.519938 1.4986)
			(layers "F.Cu" "F.Mask" "F.Paste")
			(net "M_F_CPU0_SA_DQS_DN<0>")
		)
		(pad "13" smd rect
			(at -2.050034 -53.125116 90)
			(size 0.519938 1.4986)
			(layers "F.Cu" "F.Mask" "F.Paste")
			(net "GND")
		)
		(pad "14" smd rect
			(at -2.050034 -52.274978 90)
			(size 0.519938 1.4986)
			(layers "F.Cu" "F.Mask" "F.Paste")
			(net "M_F_CPU0_SA_DQ<4>")
		)
		(pad "15" smd rect
			(at -2.050034 -51.425094 90)
			(size 0.519938 1.4986)
			(layers "F.Cu" "F.Mask" "F.Paste")
			(net "GND")
		)
		(pad "16" smd rect
			(at -2.050034 -50.574956 90)
			(size 0.519938 1.4986)
			(layers "F.Cu" "F.Mask" "F.Paste")
			(net "M_F_CPU0_SA_DQ<5>")
		)
		(pad "17" smd rect
			(at -2.050034 -49.725072 90)
			(size 0.519938 1.4986)
			(layers "F.Cu" "F.Mask" "F.Paste")
			(net "GND")
		)
		(pad "18" smd rect
			(at -2.050034 -48.874934 90)
			(size 0.519938 1.4986)
			(layers "F.Cu" "F.Mask" "F.Paste")
			(net "M_F_CPU0_SA_DQ<8>")
		)
		(pad "19" smd rect
			(at -2.050034 -48.02505 90)
			(size 0.519938 1.4986)
			(layers "F.Cu" "F.Mask" "F.Paste")
			(net "GND")
		)
		(pad "20" smd rect
			(at -2.050034 -47.174912 90)
			(size 0.519938 1.4986)
			(layers "F.Cu" "F.Mask" "F.Paste")
			(net "M_F_CPU0_SA_DQ<9>")
		)
		(pad "21" smd rect
			(at -2.050034 -46.325028 90)
			(size 0.519938 1.4986)
			(layers "F.Cu" "F.Mask" "F.Paste")
			(net "GND")
		)
		(pad "22" smd rect
			(at -2.050034 -45.47489 90)
			(size 0.519938 1.4986)
			(layers "F.Cu" "F.Mask" "F.Paste")
			(net "M_F_CPU0_SA_DQS_DP<1>")
		)
		(pad "23" smd rect
			(at -2.050034 -44.625006 90)
			(size 0.519938 1.4986)
			(layers "F.Cu" "F.Mask" "F.Paste")
			(net "M_F_CPU0_SA_DQS_DN<1>")
		)
		(pad "24" smd rect
			(at -2.050034 -43.775122 90)
			(size 0.519938 1.4986)
			(layers "F.Cu" "F.Mask" "F.Paste")
			(net "GND")
		)
		(pad "25" smd rect
			(at -2.050034 -42.924984 90)
			(size 0.519938 1.4986)
			(layers "F.Cu" "F.Mask" "F.Paste")
			(net "M_F_CPU0_SA_DQ<12>")
		)
		(pad "26" smd rect
			(at -2.050034 -42.0751 90)
			(size 0.519938 1.4986)
			(layers "F.Cu" "F.Mask" "F.Paste")
			(net "GND")
		)
		(pad "27" smd rect
			(at -2.050034 -41.224962 90)
			(size 0.519938 1.4986)
			(layers "F.Cu" "F.Mask" "F.Paste")
			(net "M_F_CPU0_SA_DQ<13>")
		)
		(pad "28" smd rect
			(at -2.050034 -40.375078 90)
			(size 0.519938 1.4986)
			(layers "F.Cu" "F.Mask" "F.Paste")
			(net "GND")
		)
		(pad "29" smd rect
			(at -2.050034 -39.52494 90)
			(size 0.519938 1.4986)
			(layers "F.Cu" "F.Mask" "F.Paste")
			(net "M_F_CPU0_SA_DQ<16>")
		)
		(pad "30" smd rect
			(at -2.050034 -38.675056 90)
			(size 0.519938 1.4986)
			(layers "F.Cu" "F.Mask" "F.Paste")
			(net "GND")
		)
		(pad "31" smd rect
			(at -2.050034 -37.824918 90)
			(size 0.519938 1.4986)
			(layers "F.Cu" "F.Mask" "F.Paste")
			(net "M_F_CPU0_SA_DQ<17>")
		)
		(pad "32" smd rect
			(at -2.050034 -36.975034 90)
			(size 0.519938 1.4986)
			(layers "F.Cu" "F.Mask" "F.Paste")
			(net "GND")
		)
		(pad "33" smd rect
			(at -2.050034 -36.124896 90)
			(size 0.519938 1.4986)
			(layers "F.Cu" "F.Mask" "F.Paste")
			(net "M_F_CPU0_SA_DQS_DP<2>")
		)
		(pad "34" smd rect
			(at -2.050034 -35.275012 90)
			(size 0.519938 1.4986)
			(layers "F.Cu" "F.Mask" "F.Paste")
			(net "M_F_CPU0_SA_DQS_DN<2>")
		)
		(pad "35" smd rect
			(at -2.050034 -34.425128 90)
			(size 0.519938 1.4986)
			(layers "F.Cu" "F.Mask" "F.Paste")
			(net "GND")
		)
		(pad "36" smd rect
			(at -2.050034 -33.57499 90)
			(size 0.519938 1.4986)
			(layers "F.Cu" "F.Mask" "F.Paste")
			(net "M_F_CPU0_SA_DQ<20>")
		)
		(pad "37" smd rect
			(at -2.050034 -32.725106 90)
			(size 0.519938 1.4986)
			(layers "F.Cu" "F.Mask" "F.Paste")
			(net "GND")
		)
		(pad "38" smd rect
			(at -2.050034 -31.874968 90)
			(size 0.519938 1.4986)
			(layers "F.Cu" "F.Mask" "F.Paste")
			(net "M_F_CPU0_SA_DQ<21>")
		)
		(pad "39" smd rect
			(at -2.050034 -31.025084 90)
			(size 0.519938 1.4986)
			(layers "F.Cu" "F.Mask" "F.Paste")
			(net "GND")
		)
		(pad "40" smd rect
			(at -2.050034 -30.174946 90)
			(size 0.519938 1.4986)
			(layers "F.Cu" "F.Mask" "F.Paste")
			(net "M_F_CPU0_SA_DQ<24>")
		)
		(pad "41" smd rect
			(at -2.050034 -29.325062 90)
			(size 0.519938 1.4986)
			(layers "F.Cu" "F.Mask" "F.Paste")
			(net "GND")
		)
		(pad "42" smd rect
			(at -2.050034 -28.474924 90)
			(size 0.519938 1.4986)
			(layers "F.Cu" "F.Mask" "F.Paste")
			(net "M_F_CPU0_SA_DQ<25>")
		)
		(pad "43" smd rect
			(at -2.050034 -27.62504 90)
			(size 0.519938 1.4986)
			(layers "F.Cu" "F.Mask" "F.Paste")
			(net "GND")
		)
		(pad "44" smd rect
			(at -2.050034 -26.774902 90)
			(size 0.519938 1.4986)
			(layers "F.Cu" "F.Mask" "F.Paste")
			(net "M_F_CPU0_SA_DQS_DP<3>")
		)
		(pad "45" smd rect
			(at -2.050034 -25.925018 90)
			(size 0.519938 1.4986)
			(layers "F.Cu" "F.Mask" "F.Paste")
			(net "M_F_CPU0_SA_DQS_DN<3>")
		)
		(pad "46" smd rect
			(at -2.050034 -25.07488 90)
			(size 0.519938 1.4986)
			(layers "F.Cu" "F.Mask" "F.Paste")
			(net "GND")
		)
	)
)
